(kicad_pcb
	(version 20260206)
	(generator "pcbnew")
	(generator_version "10.0")
	(general
		(thickness 1.6)
		(legacy_teardrops no)
	)
	(paper "A4")
	(title_block
		(title "03242023_DA0F0TMBIJ0_F0T_Motherboard_J_brd_V01_OCP.brd")
		(comment 1 "Grand Teton / footprints 4514-4520 of 6105")
	)
	(layers
		(0 "F.Cu" signal "TOP")
		(4 "In1.Cu" signal "GND")
		(6 "In2.Cu" signal "IN1")
		(8 "In3.Cu" signal "GND1")
		(10 "In4.Cu" signal "IN2")
		(12 "In5.Cu" signal "GND2")
		(14 "In6.Cu" signal "IN3")
		(16 "In7.Cu" signal "GND3")
		(18 "In8.Cu" signal "VCC")
		(20 "In9.Cu" signal "VCC1")
		(22 "In10.Cu" signal "GND4")
		(24 "In11.Cu" signal "IN4")
		(26 "In12.Cu" signal "GND5")
		(28 "In13.Cu" signal "IN5")
		(30 "In14.Cu" signal "GND6")
		(32 "In15.Cu" signal "IN6")
		(34 "In16.Cu" signal "GND7")
		(2 "B.Cu" signal "BOTTOM")
		(9 "F.Adhes" user "F.Adhesive")
		(11 "B.Adhes" user "B.Adhesive")
		(13 "F.Paste" user "Package Geometry/Pastemask Top")
		(15 "B.Paste" user "Package Geometry/Pastemask Bottom")
		(5 "F.SilkS" user "Ref Des/Silkscreen Top")
		(7 "B.SilkS" user "Ref Des/Silkscreen Bottom")
		(1 "F.Mask" user "Board Geometry/Soldermask Top")
		(3 "B.Mask" user "Board Geometry/Soldermask Bottom")
		(17 "Dwgs.User" user "User.Drawings")
		(19 "Cmts.User" user "User.Comments")
		(21 "Eco1.User" user "User.Eco1")
		(23 "Eco2.User" user "User.Eco2")
		(25 "Edge.Cuts" user "Board Geometry/Outline")
		(27 "Margin" user)
		(31 "F.CrtYd" user "Package Geometry/Place Bound Top")
		(29 "B.CrtYd" user "Package Geometry/Place Bound Bottom")
		(35 "F.Fab" user "Ref Des/Assembly Top")
		(33 "B.Fab" user "Ref Des/Assembly Bottom")
	)
	(footprint ""
		(layer "B.Cu")
		(at 18.613374 -176.431194 90)
		(property "Reference" "R2384"
			(at 0 0 90)
			(layer "B.SilkS")
			(hide yes)
			(effects
				(font
					(size 1.27 1.27)
				)
				(justify mirror)
			)
		)
		(property "Value" ""
			(at 0 0 90)
			(layer "B.Fab")
			(effects
				(font
					(size 1.27 1.27)
				)
				(justify mirror)
			)
		)
		(duplicate_pad_numbers_are_jumpers no)
		(fp_line
			(start 0.7874 -0.4064)
			(end -0.7874 -0.4064)
			(stroke
				(width 0.1524)
				(type default)
			)
			(layer "B.SilkS")
		)
		(fp_line
			(start -0.7874 -0.4064)
			(end -0.7874 0.4064)
			(stroke
				(width 0.1524)
				(type default)
			)
			(layer "B.SilkS")
		)
		(fp_line
			(start 0.7874 0.4064)
			(end 0.7874 -0.4064)
			(stroke
				(width 0.1524)
				(type default)
			)
			(layer "B.SilkS")
		)
		(fp_line
			(start -0.7874 0.4064)
			(end 0.7874 0.4064)
			(stroke
				(width 0.1524)
				(type default)
			)
			(layer "B.SilkS")
		)
		(fp_line
			(start 0.67945 -0.305054)
			(end 0.12065 -0.305054)
			(stroke
				(width 0.1)
				(type default)
			)
			(layer "B.Fab")
		)
		(fp_line
			(start 0.12065 -0.305054)
			(end 0.12065 -0.2794)
			(stroke
				(width 0.1)
				(type default)
			)
			(layer "B.Fab")
		)
		(fp_line
			(start -0.12065 -0.3048)
			(end -0.67945 -0.3048)
			(stroke
				(width 0.1)
				(type default)
			)
			(layer "B.Fab")
		)
		(fp_line
			(start -0.67945 -0.3048)
			(end -0.67945 0.3048)
			(stroke
				(width 0.1)
				(type default)
			)
			(layer "B.Fab")
		)
		(fp_line
			(start 0.12065 -0.2794)
			(end -0.12065 -0.2794)
			(stroke
				(width 0.1)
				(type default)
			)
			(layer "B.Fab")
		)
		(fp_line
			(start -0.12065 -0.2794)
			(end -0.12065 -0.3048)
			(stroke
				(width 0.1)
				(type default)
			)
			(layer "B.Fab")
		)
		(fp_line
			(start 0.12065 0.2794)
			(end 0.12065 0.3048)
			(stroke
				(width 0.1)
				(type default)
			)
			(layer "B.Fab")
		)
		(fp_line
			(start -0.120396 0.2794)
			(end 0.12065 0.2794)
			(stroke
				(width 0.1)
				(type default)
			)
			(layer "B.Fab")
		)
		(fp_line
			(start 0.67945 0.3048)
			(end 0.67945 -0.305054)
			(stroke
				(width 0.1)
				(type default)
			)
			(layer "B.Fab")
		)
		(fp_line
			(start 0.12065 0.3048)
			(end 0.67945 0.3048)
			(stroke
				(width 0.1)
				(type default)
			)
			(layer "B.Fab")
		)
		(fp_line
			(start -0.120396 0.3048)
			(end -0.120396 0.2794)
			(stroke
				(width 0.1)
				(type default)
			)
			(layer "B.Fab")
		)
		(fp_line
			(start -0.67945 0.3048)
			(end -0.120396 0.3048)
			(stroke
				(width 0.1)
				(type default)
			)
			(layer "B.Fab")
		)
		(pad "1" smd circle
			(at 0.40005 0 270)
			(size 0 0)
			(layers "B.Cu" "B.Mask" "B.Paste")
			(net "P3V3_AUX")
		)
		(pad "2" smd circle
			(at -0.40005 0 270)
			(size 0 0)
			(layers "B.Cu" "B.Mask" "B.Paste")
			(net "FM_PVNN_MAIN_CPU1_EN")
		)
	)
	(footprint ""
		(layer "B.Cu")
		(at 240.3094 -422.9862 90)
		(property "Reference" "C2296"
			(at 0 0 90)
			(layer "B.SilkS")
			(hide yes)
			(effects
				(font
					(size 1.27 1.27)
				)
				(justify mirror)
			)
		)
		(property "Value" ""
			(at 0 0 90)
			(layer "B.Fab")
			(effects
				(font
					(size 1.27 1.27)
				)
				(justify mirror)
			)
		)
		(duplicate_pad_numbers_are_jumpers no)
		(fp_line
			(start 0.7874 -0.4064)
			(end -0.7874 -0.4064)
			(stroke
				(width 0.1524)
				(type default)
			)
			(layer "B.SilkS")
		)
		(fp_line
			(start -0.7874 -0.4064)
			(end -0.7874 0.4064)
			(stroke
				(width 0.1524)
				(type default)
			)
			(layer "B.SilkS")
		)
		(fp_line
			(start 0.7874 0.4064)
			(end 0.7874 -0.4064)
			(stroke
				(width 0.1524)
				(type default)
			)
			(layer "B.SilkS")
		)
		(fp_line
			(start -0.7874 0.4064)
			(end 0.7874 0.4064)
			(stroke
				(width 0.1524)
				(type default)
			)
			(layer "B.SilkS")
		)
		(fp_line
			(start 0.67945 -0.305054)
			(end 0.12065 -0.305054)
			(stroke
				(width 0.1)
				(type default)
			)
			(layer "B.Fab")
		)
		(fp_line
			(start 0.12065 -0.305054)
			(end 0.12065 -0.2794)
			(stroke
				(width 0.1)
				(type default)
			)
			(layer "B.Fab")
		)
		(fp_line
			(start -0.12065 -0.3048)
			(end -0.67945 -0.3048)
			(stroke
				(width 0.1)
				(type default)
			)
			(layer "B.Fab")
		)
		(fp_line
			(start -0.67945 -0.3048)
			(end -0.67945 0.3048)
			(stroke
				(width 0.1)
				(type default)
			)
			(layer "B.Fab")
		)
		(fp_line
			(start 0.12065 -0.2794)
			(end -0.12065 -0.2794)
			(stroke
				(width 0.1)
				(type default)
			)
			(layer "B.Fab")
		)
		(fp_line
			(start -0.12065 -0.2794)
			(end -0.12065 -0.3048)
			(stroke
				(width 0.1)
				(type default)
			)
			(layer "B.Fab")
		)
		(fp_line
			(start 0.12065 0.2794)
			(end 0.12065 0.3048)
			(stroke
				(width 0.1)
				(type default)
			)
			(layer "B.Fab")
		)
		(fp_line
			(start -0.120396 0.2794)
			(end 0.12065 0.2794)
			(stroke
				(width 0.1)
				(type default)
			)
			(layer "B.Fab")
		)
		(fp_line
			(start 0.67945 0.3048)
			(end 0.67945 -0.305054)
			(stroke
				(width 0.1)
				(type default)
			)
			(layer "B.Fab")
		)
		(fp_line
			(start 0.12065 0.3048)
			(end 0.67945 0.3048)
			(stroke
				(width 0.1)
				(type default)
			)
			(layer "B.Fab")
		)
		(fp_line
			(start -0.120396 0.3048)
			(end -0.120396 0.2794)
			(stroke
				(width 0.1)
				(type default)
			)
			(layer "B.Fab")
		)
		(fp_line
			(start -0.67945 0.3048)
			(end -0.120396 0.3048)
			(stroke
				(width 0.1)
				(type default)
			)
			(layer "B.Fab")
		)
		(pad "1" smd circle
			(at 0.40005 0 270)
			(size 0 0)
			(layers "B.Cu" "B.Mask" "B.Paste")
			(net "FM_FAN_PWR_EN_R")
		)
		(pad "2" smd circle
			(at -0.40005 0 270)
			(size 0 0)
			(layers "B.Cu" "B.Mask" "B.Paste")
			(net "GND")
		)
	)
	(footprint ""
		(layer "B.Cu")
		(at 114.440462 -333.73568 90)
		(property "Reference" "PC536_P1_3"
			(at 0 0 90)
			(layer "B.SilkS")
			(hide yes)
			(effects
				(font
					(size 1.27 1.27)
				)
				(justify mirror)
			)
		)
		(property "Value" ""
			(at 0 0 90)
			(layer "B.Fab")
			(effects
				(font
					(size 1.27 1.27)
				)
				(justify mirror)
			)
		)
		(duplicate_pad_numbers_are_jumpers no)
		(fp_line
			(start 1.524 -0.762)
			(end -1.524 -0.762)
			(stroke
				(width 0.1524)
				(type default)
			)
			(layer "B.SilkS")
		)
		(fp_line
			(start -1.524 -0.762)
			(end -1.524 0.762)
			(stroke
				(width 0.1524)
				(type default)
			)
			(layer "B.SilkS")
		)
		(fp_line
			(start 1.524 0.762)
			(end 1.524 -0.762)
			(stroke
				(width 0.1524)
				(type default)
			)
			(layer "B.SilkS")
		)
		(fp_line
			(start -1.524 0.762)
			(end 1.524 0.762)
			(stroke
				(width 0.1524)
				(type default)
			)
			(layer "B.SilkS")
		)
		(fp_line
			(start 1.1049 -0.724916)
			(end 1.1049 0.724916)
			(stroke
				(width 0.1)
				(type default)
			)
			(layer "B.Fab")
		)
		(fp_line
			(start -1.1049 -0.724916)
			(end 1.1049 -0.724916)
			(stroke
				(width 0.1)
				(type default)
			)
			(layer "B.Fab")
		)
		(fp_line
			(start 1.1049 0.724916)
			(end -1.1049 0.724916)
			(stroke
				(width 0.1)
				(type default)
			)
			(layer "B.Fab")
		)
		(fp_line
			(start -1.1049 0.724916)
			(end -1.1049 -0.724916)
			(stroke
				(width 0.1)
				(type default)
			)
			(layer "B.Fab")
		)
		(pad "1" smd rect
			(at 0.889 0 90)
			(size 1.016 1.27)
			(layers "B.Cu" "B.Mask" "B.Paste")
			(net "SW_P12V_PVCCIN_CPU1_FLT")
		)
		(pad "2" smd rect
			(at -0.889 0 90)
			(size 1.016 1.27)
			(layers "B.Cu" "B.Mask" "B.Paste")
			(net "GND")
		)
	)
	(footprint ""
		(layer "B.Cu")
		(at 24.352504 -175.819562 90)
		(property "Reference" "R2387"
			(at 0 0 90)
			(layer "B.SilkS")
			(hide yes)
			(effects
				(font
					(size 1.27 1.27)
				)
				(justify mirror)
			)
		)
		(property "Value" ""
			(at 0 0 90)
			(layer "B.Fab")
			(effects
				(font
					(size 1.27 1.27)
				)
				(justify mirror)
			)
		)
		(duplicate_pad_numbers_are_jumpers no)
		(fp_line
			(start 0.7874 -0.4064)
			(end -0.7874 -0.4064)
			(stroke
				(width 0.1524)
				(type default)
			)
			(layer "B.SilkS")
		)
		(fp_line
			(start -0.7874 -0.4064)
			(end -0.7874 0.4064)
			(stroke
				(width 0.1524)
				(type default)
			)
			(layer "B.SilkS")
		)
		(fp_line
			(start 0.7874 0.4064)
			(end 0.7874 -0.4064)
			(stroke
				(width 0.1524)
				(type default)
			)
			(layer "B.SilkS")
		)
		(fp_line
			(start -0.7874 0.4064)
			(end 0.7874 0.4064)
			(stroke
				(width 0.1524)
				(type default)
			)
			(layer "B.SilkS")
		)
		(fp_line
			(start 0.67945 -0.305054)
			(end 0.12065 -0.305054)
			(stroke
				(width 0.1)
				(type default)
			)
			(layer "B.Fab")
		)
		(fp_line
			(start 0.12065 -0.305054)
			(end 0.12065 -0.2794)
			(stroke
				(width 0.1)
				(type default)
			)
			(layer "B.Fab")
		)
		(fp_line
			(start -0.12065 -0.3048)
			(end -0.67945 -0.3048)
			(stroke
				(width 0.1)
				(type default)
			)
			(layer "B.Fab")
		)
		(fp_line
			(start -0.67945 -0.3048)
			(end -0.67945 0.3048)
			(stroke
				(width 0.1)
				(type default)
			)
			(layer "B.Fab")
		)
		(fp_line
			(start 0.12065 -0.2794)
			(end -0.12065 -0.2794)
			(stroke
				(width 0.1)
				(type default)
			)
			(layer "B.Fab")
		)
		(fp_line
			(start -0.12065 -0.2794)
			(end -0.12065 -0.3048)
			(stroke
				(width 0.1)
				(type default)
			)
			(layer "B.Fab")
		)
		(fp_line
			(start 0.12065 0.2794)
			(end 0.12065 0.3048)
			(stroke
				(width 0.1)
				(type default)
			)
			(layer "B.Fab")
		)
		(fp_line
			(start -0.120396 0.2794)
			(end 0.12065 0.2794)
			(stroke
				(width 0.1)
				(type default)
			)
			(layer "B.Fab")
		)
		(fp_line
			(start 0.67945 0.3048)
			(end 0.67945 -0.305054)
			(stroke
				(width 0.1)
				(type default)
			)
			(layer "B.Fab")
		)
		(fp_line
			(start 0.12065 0.3048)
			(end 0.67945 0.3048)
			(stroke
				(width 0.1)
				(type default)
			)
			(layer "B.Fab")
		)
		(fp_line
			(start -0.120396 0.3048)
			(end -0.120396 0.2794)
			(stroke
				(width 0.1)
				(type default)
			)
			(layer "B.Fab")
		)
		(fp_line
			(start -0.67945 0.3048)
			(end -0.120396 0.3048)
			(stroke
				(width 0.1)
				(type default)
			)
			(layer "B.Fab")
		)
		(pad "1" smd circle
			(at 0.40005 0 270)
			(size 0 0)
			(layers "B.Cu" "B.Mask" "B.Paste")
			(net "PWRGD_PVNN_MAIN_CPU1_R")
		)
		(pad "2" smd circle
			(at -0.40005 0 270)
			(size 0 0)
			(layers "B.Cu" "B.Mask" "B.Paste")
			(net "PWRGD_PVNN_MAIN_CPU1")
		)
	)
	(footprint ""
		(layer "B.Cu")
		(at 260.157214 -321.549776 -90)
		(property "Reference" "C21"
			(at 0 0 90)
			(layer "B.SilkS")
			(hide yes)
			(effects
				(font
					(size 1.27 1.27)
				)
				(justify mirror)
			)
		)
		(property "Value" ""
			(at 0 0 90)
			(layer "B.Fab")
			(effects
				(font
					(size 1.27 1.27)
				)
				(justify mirror)
			)
		)
		(duplicate_pad_numbers_are_jumpers no)
		(fp_line
			(start -1.524 0.762)
			(end 1.524 0.762)
			(stroke
				(width 0.1524)
				(type default)
			)
			(layer "B.SilkS")
		)
		(fp_line
			(start 1.524 0.762)
			(end 1.524 -0.762)
			(stroke
				(width 0.1524)
				(type default)
			)
			(layer "B.SilkS")
		)
		(fp_line
			(start -1.524 -0.762)
			(end -1.524 0.762)
			(stroke
				(width 0.1524)
				(type default)
			)
			(layer "B.SilkS")
		)
		(fp_line
			(start 1.524 -0.762)
			(end -1.524 -0.762)
			(stroke
				(width 0.1524)
				(type default)
			)
			(layer "B.SilkS")
		)
		(fp_line
			(start -1.1049 0.724916)
			(end -1.1049 -0.724916)
			(stroke
				(width 0.1)
				(type default)
			)
			(layer "B.Fab")
		)
		(fp_line
			(start 1.1049 0.724916)
			(end -1.1049 0.724916)
			(stroke
				(width 0.1)
				(type default)
			)
			(layer "B.Fab")
		)
		(fp_line
			(start -1.1049 -0.724916)
			(end 1.1049 -0.724916)
			(stroke
				(width 0.1)
				(type default)
			)
			(layer "B.Fab")
		)
		(fp_line
			(start 1.1049 -0.724916)
			(end 1.1049 0.724916)
			(stroke
				(width 0.1)
				(type default)
			)
			(layer "B.Fab")
		)
		(pad "1" smd rect
			(at 0.889 0 270)
			(size 1.016 1.27)
			(layers "B.Cu" "B.Mask" "B.Paste")
			(net "P12V_S3_AUX_CPU0_NVDIMM")
		)
		(pad "2" smd rect
			(at -0.889 0 270)
			(size 1.016 1.27)
			(layers "B.Cu" "B.Mask" "B.Paste")
			(net "GND")
		)
	)
	(footprint ""
		(layer "B.Cu")
		(at 269.179294 -64.432434)
		(property "Reference" "PC1229"
			(at 0 0 0)
			(layer "B.SilkS")
			(hide yes)
			(effects
				(font
					(size 1.27 1.27)
				)
				(justify mirror)
			)
		)
		(property "Value" ""
			(at 0 0 0)
			(layer "B.Fab")
			(effects
				(font
					(size 1.27 1.27)
				)
				(justify mirror)
			)
		)
		(duplicate_pad_numbers_are_jumpers no)
		(fp_line
			(start -4.53898 -2.15011)
			(end -4.53898 2.15011)
			(stroke
				(width 0.1524)
				(type default)
			)
			(layer "B.SilkS")
		)
		(fp_line
			(start -4.53898 2.15011)
			(end 4.53898 2.15011)
			(stroke
				(width 0.1524)
				(type default)
			)
			(layer "B.SilkS")
		)
		(fp_line
			(start 4.53898 -2.150618)
			(end 4.539742 2.152142)
			(stroke
				(width 0.1524)
				(type default)
			)
			(layer "B.SilkS")
		)
		(fp_line
			(start 4.53898 -2.15011)
			(end -4.53898 -2.15011)
			(stroke
				(width 0.1524)
				(type default)
			)
			(layer "B.SilkS")
		)
		(fp_line
			(start 4.53898 2.15011)
			(end 4.53898 -2.15011)
			(stroke
				(width 0.1524)
				(type default)
			)
			(layer "B.SilkS")
		)
		(fp_line
			(start 4.69138 -2.150618)
			(end 4.692396 2.161032)
			(stroke
				(width 0.1524)
				(type default)
			)
			(layer "B.SilkS")
		)
		(fp_line
			(start 4.83108 2.150364)
			(end 4.447794 2.149348)
			(stroke
				(width 0.1524)
				(type default)
			)
			(layer "B.SilkS")
		)
		(fp_line
			(start 4.84378 -2.150618)
			(end 4.53898 -2.150618)
			(stroke
				(width 0.1524)
				(type default)
			)
			(layer "B.SilkS")
		)
		(fp_line
			(start 4.84378 -2.150618)
			(end 4.842256 2.163064)
			(stroke
				(width 0.1524)
				(type default)
			)
			(layer "B.SilkS")
		)
		(fp_line
			(start -3.64998 -2.15011)
			(end -3.64998 2.15011)
			(stroke
				(width 0.1)
				(type default)
			)
			(layer "B.Fab")
		)
		(fp_line
			(start -3.64998 2.15011)
			(end 3.64998 2.15011)
			(stroke
				(width 0.1)
				(type default)
			)
			(layer "B.Fab")
		)
		(fp_line
			(start 3.64998 -2.15011)
			(end -3.64998 -2.15011)
			(stroke
				(width 0.1)
				(type default)
			)
			(layer "B.Fab")
		)
		(fp_line
			(start 3.64998 2.15011)
			(end 3.64998 -2.15011)
			(stroke
				(width 0.1)
				(type default)
			)
			(layer "B.Fab")
		)
		(fp_text user "-"
			(at -4.658614 2.955036 0)
			(unlocked yes)
			(layer "B.SilkS")
			(effects
				(font
					(size 1.905 1.4224)
					(thickness 0.1524)
				)
				(justify left mirror)
			)
		)
		(fp_text user "+"
			(at 6.214872 -0.337058 0)
			(unlocked yes)
			(layer "B.SilkS")
			(effects
				(font
					(size 1.905 1.4224)
					(thickness 0.1524)
				)
				(justify left mirror)
			)
		)
		(fp_text user "-"
			(at -4.313174 -0.094488 0)
			(unlocked yes)
			(layer "B.Fab")
			(effects
				(font
					(size 1.905 1.4224)
					(thickness 0.1524)
				)
				(justify left mirror)
			)
		)
		(fp_text user "+"
			(at 6.214872 -0.337058 0)
			(unlocked yes)
			(layer "B.Fab")
			(effects
				(font
					(size 1.905 1.4224)
					(thickness 0.1524)
				)
				(justify left mirror)
			)
		)
		(pad "1" smd rect
			(at 3.199892 0 180)
			(size 2.413 2.8194)
			(layers "B.Cu" "B.Mask" "B.Paste")
			(net "P1V05_PCH_AUX")
		)
		(pad "2" smd rect
			(at -3.199892 0 180)
			(size 2.413 2.8194)
			(layers "B.Cu" "B.Mask" "B.Paste")
			(net "GND")
		)
	)
	(footprint ""
		(layer "B.Cu")
		(at 115.66652 -355.925628)
		(property "Reference" "R2524"
			(at 0 0 0)
			(layer "B.SilkS")
			(hide yes)
			(effects
				(font
					(size 1.27 1.27)
				)
				(justify mirror)
			)
		)
		(property "Value" ""
			(at 0 0 0)
			(layer "B.Fab")
			(effects
				(font
					(size 1.27 1.27)
				)
				(justify mirror)
			)
		)
		(duplicate_pad_numbers_are_jumpers no)
		(fp_line
			(start -0.7874 -0.4064)
			(end -0.7874 0.4064)
			(stroke
				(width 0.1524)
				(type default)
			)
			(layer "B.SilkS")
		)
		(fp_line
			(start -0.7874 0.4064)
			(end 0.7874 0.4064)
			(stroke
				(width 0.1524)
				(type default)
			)
			(layer "B.SilkS")
		)
		(fp_line
			(start 0.7874 -0.4064)
			(end -0.7874 -0.4064)
			(stroke
				(width 0.1524)
				(type default)
			)
			(layer "B.SilkS")
		)
		(fp_line
			(start 0.7874 0.4064)
			(end 0.7874 -0.4064)
			(stroke
				(width 0.1524)
				(type default)
			)
			(layer "B.SilkS")
		)
		(fp_line
			(start -0.67945 -0.3048)
			(end -0.67945 0.3048)
			(stroke
				(width 0.1)
				(type default)
			)
			(layer "B.Fab")
		)
		(fp_line
			(start -0.67945 0.3048)
			(end -0.120396 0.3048)
			(stroke
				(width 0.1)
				(type default)
			)
			(layer "B.Fab")
		)
		(fp_line
			(start -0.12065 -0.3048)
			(end -0.67945 -0.3048)
			(stroke
				(width 0.1)
				(type default)
			)
			(layer "B.Fab")
		)
		(fp_line
			(start -0.12065 -0.2794)
			(end -0.12065 -0.3048)
			(stroke
				(width 0.1)
				(type default)
			)
			(layer "B.Fab")
		)
		(fp_line
			(start -0.120396 0.2794)
			(end 0.12065 0.2794)
			(stroke
				(width 0.1)
				(type default)
			)
			(layer "B.Fab")
		)
		(fp_line
			(start -0.120396 0.3048)
			(end -0.120396 0.2794)
			(stroke
				(width 0.1)
				(type default)
			)
			(layer "B.Fab")
		)
		(fp_line
			(start 0.12065 -0.305054)
			(end 0.12065 -0.2794)
			(stroke
				(width 0.1)
				(type default)
			)
			(layer "B.Fab")
		)
		(fp_line
			(start 0.12065 -0.2794)
			(end -0.12065 -0.2794)
			(stroke
				(width 0.1)
				(type default)
			)
			(layer "B.Fab")
		)
		(fp_line
			(start 0.12065 0.2794)
			(end 0.12065 0.3048)
			(stroke
				(width 0.1)
				(type default)
			)
			(layer "B.Fab")
		)
		(fp_line
			(start 0.12065 0.3048)
			(end 0.67945 0.3048)
			(stroke
				(width 0.1)
				(type default)
			)
			(layer "B.Fab")
		)
		(fp_line
			(start 0.67945 -0.305054)
			(end 0.12065 -0.305054)
			(stroke
				(width 0.1)
				(type default)
			)
			(layer "B.Fab")
		)
		(fp_line
			(start 0.67945 0.3048)
			(end 0.67945 -0.305054)
			(stroke
				(width 0.1)
				(type default)
			)
			(layer "B.Fab")
		)
		(pad "1" smd circle
			(at 0.40005 0 180)
			(size 0 0)
			(layers "B.Cu" "B.Mask" "B.Paste")
			(net "P3V3_AUX")
		)
		(pad "2" smd circle
			(at -0.40005 0 180)
			(size 0 0)
			(layers "B.Cu" "B.Mask" "B.Paste")
			(net "PVCCIN_CPU1_VR_FAULT")
		)
	)
)
